(kicad_pcb
	(version 20221018)
	(generator pcbnew)
	(general
    (thickness 1.7403)
  )
	(paper "A4")
	(title_block
    (title "Data Center RDIMM DDR4 Tester")
    (date "2024-09-30")
    (rev "1.2.4")
		(comment 9 "footprint 168 of 690 (U15), pads 180-267 of 676")
	)
	(layers
    (0 "F.Cu" signal)
    (1 "In1.Cu" power)
    (2 "In2.Cu" signal)
    (3 "In3.Cu" power)
    (4 "In4.Cu" power)
    (5 "In5.Cu" signal)
    (6 "In6.Cu" power)
    (7 "In7.Cu" signal)
    (8 "In8.Cu" power)
    (9 "In9.Cu" signal)
    (10 "In10.Cu" power)
    (31 "B.Cu" signal)
    (32 "B.Adhes" user "B.Adhesive")
    (33 "F.Adhes" user "F.Adhesive")
    (34 "B.Paste" user)
    (35 "F.Paste" user)
    (36 "B.SilkS" user "B.Silkscreen")
    (37 "F.SilkS" user "F.Silkscreen")
    (38 "B.Mask" user)
    (39 "F.Mask" user)
    (40 "Dwgs.User" user "User.Drawings")
    (41 "Cmts.User" user "User.Comments")
    (42 "Eco1.User" user "User.Eco1")
    (43 "Eco2.User" user "User.Eco2")
    (44 "Edge.Cuts" user)
    (45 "Margin" user)
    (46 "B.CrtYd" user "B.Courtyard")
    (47 "F.CrtYd" user "F.Courtyard")
    (48 "B.Fab" user)
    (49 "F.Fab" user)
  )
	(footprint "data-center-rdimm-ddr4-tester-footprints:BGA-676_27x27mm_Layout26x26_P1X1mm"
    (layer "F.Cu")
    (at 183.635 90.06 180)
    (descr "FPGA XC7K160TFBG676")
    (tags "FPGA XC7K160TFBG676")
    (property "Author" "Antmicro")
    (property "License" "Apache-2.0")
    (property "MPN" "XC7K160T-FFG676")
    (property "Manufacturer" "AMD-Xilinx")
    (property "Sheetfile" "config-spi.kicad_sch")
    (property "Sheetname" "Config SPI flash")
    (property "ki_description" "Kintex®-7 Field Programmable Gate Array (FPGA) IC 300 4976640 65600 676-BBGA, FCBGA")
    (property "ki_keywords" "SMT, MICROCONTROLLER, IC, FPGA")
    (attr smd)
    (fp_text reference "U15" (at -10.675 -14.7 180) (layer "F.SilkS")
        (effects (font (size 0.7 0.7) (thickness 0.15)) (justify left bottom))
    )
    (fp_text value "XC7K160T-FFG676" (at 0 15.5 180) (layer "F.Fab")
        (effects (font (size 0.7 0.7) (thickness 0.15)) (justify left bottom))
    )
    (pad "AF24" smd circle (at 10.499 12.499 180) (size 0.5 0.5) (layers "F.Cu" "F.Paste" "F.Mask")
      (net 166 "HR_DQ2") (pinfunction "IO_L20P_T3_12") (pintype "bidirectional") (die_length 17.799))
    (pad "AF25" smd circle (at 11.499 12.499 180) (size 0.5 0.5) (layers "F.Cu" "F.Paste" "F.Mask")
      (net 160 "HR_DQ5") (pinfunction "IO_L20N_T3_12") (pintype "bidirectional") (die_length 18.603))
    (pad "AF26" smd circle (at 12.499 12.499 180) (size 0.5 0.5) (layers "F.Cu" "F.Paste" "F.Mask")
      (net 143 "3V3_SYS") (pinfunction "VCCO_12") (pintype "passive"))
    (pad "B1" smd circle (at -12.5 -11.5 180) (size 0.5 0.5) (layers "F.Cu" "F.Paste" "F.Mask")
      (net 429 "GTX_TX1_N") (pinfunction "MGTXTXN2_116") (pintype "bidirectional") (die_length 15.86))
    (pad "B2" smd circle (at -11.5 -11.5 180) (size 0.5 0.5) (layers "F.Cu" "F.Paste" "F.Mask")
      (net 420 "GTX_TX1_P") (pinfunction "MGTXTXP2_116") (pintype "bidirectional") (die_length 16.008))
    (pad "B3" smd circle (at -10.5 -11.5 180) (size 0.5 0.5) (layers "F.Cu" "F.Paste" "F.Mask")
      (net 306 "1V2_SYS") (pinfunction "MGTAVTT") (pintype "power_in"))
    (pad "B4" smd circle (at -9.5 -11.5 180) (size 0.5 0.5) (layers "F.Cu" "F.Paste" "F.Mask")
      (net 9 "GND") (pinfunction "GND") (pintype "passive"))
    (pad "B5" smd circle (at -8.5 -11.5 180) (size 0.5 0.5) (layers "F.Cu" "F.Paste" "F.Mask")
      (net 656 "GTX_RX0_N") (pinfunction "MGTXRXN3_116") (pintype "bidirectional") (die_length 13.646))
    (pad "B6" smd circle (at -7.5 -11.5 180) (size 0.5 0.5) (layers "F.Cu" "F.Paste" "F.Mask")
      (net 655 "GTX_RX0_P") (pinfunction "MGTXRXP3_116") (pintype "bidirectional") (die_length 13.747))
    (pad "B7" smd circle (at -6.5 -11.5 180) (size 0.5 0.5) (layers "F.Cu" "F.Paste" "F.Mask")
      (net 9 "GND") (pinfunction "GND") (pintype "passive"))
    (pad "B8" smd circle (at -5.5 -11.5 180) (size 0.5 0.5) (layers "F.Cu" "F.Paste" "F.Mask")
      (net 143 "3V3_SYS") (pinfunction "VCCO_16") (pintype "passive"))
    (pad "B9" smd circle (at -4.5 -11.5 180) (size 0.5 0.5) (layers "F.Cu" "F.Paste" "F.Mask")
      (net 724 "unconnected-(U15E-IO_L10N_T1_16-PadB9)") (pinfunction "IO_L10N_T1_16") (pintype "bidirectional+no_connect") (die_length 21.661))
    (pad "B10" smd circle (at -3.5 -11.5 180) (size 0.5 0.5) (layers "F.Cu" "F.Paste" "F.Mask")
      (net 61 "TMDS_D2_P") (pinfunction "IO_L22P_T3_16") (pintype "bidirectional") (die_length 19.148))
    (pad "B11" smd circle (at -2.5 -11.5 180) (size 0.5 0.5) (layers "F.Cu" "F.Paste" "F.Mask")
      (net 725 "unconnected-(U15E-IO_L20N_T3_16-PadB11)") (pinfunction "IO_L20N_T3_16") (pintype "bidirectional+no_connect") (die_length 19.129))
    (pad "B12" smd circle (at -1.5 -11.5 180) (size 0.5 0.5) (layers "F.Cu" "F.Paste" "F.Mask")
      (net 726 "unconnected-(U15E-IO_L20P_T3_16-PadB12)") (pinfunction "IO_L20P_T3_16") (pintype "bidirectional+no_connect") (die_length 19.084))
    (pad "B13" smd circle (at -0.5 -11.5 180) (size 0.5 0.5) (layers "F.Cu" "F.Paste" "F.Mask")
      (net 9 "GND") (pinfunction "GND") (pintype "passive"))
    (pad "B14" smd circle (at 0.499 -11.5 180) (size 0.5 0.5) (layers "F.Cu" "F.Paste" "F.Mask")
      (net 57 "TMDS_D0_P") (pinfunction "IO_L21P_T3_DQS_16") (pintype "bidirectional") (die_length 17.698))
    (pad "B15" smd circle (at 1.499 -11.5 180) (size 0.5 0.5) (layers "F.Cu" "F.Paste" "F.Mask")
      (net 55 "TMDS_CLK_P") (pinfunction "IO_L23P_T3_16") (pintype "bidirectional") (die_length 17.518))
    (pad "B16" smd circle (at 2.499 -11.5 180) (size 0.5 0.5) (layers "F.Cu" "F.Paste" "F.Mask")
      (net 417 "FMC_IO_1_N") (pinfunction "IO_L1N_T0_AD0N_15") (pintype "bidirectional") (die_length 16.625))
    (pad "B17" smd circle (at 3.499 -11.5 180) (size 0.5 0.5) (layers "F.Cu" "F.Paste" "F.Mask")
      (net 425 "FMC_IO_3_P") (pinfunction "IO_L3P_T0_DQS_AD1P_15") (pintype "bidirectional") (die_length 17.668))
    (pad "B18" smd circle (at 4.499 -11.5 180) (size 0.5 0.5) (layers "F.Cu" "F.Paste" "F.Mask")
      (net 143 "3V3_SYS") (pinfunction "VCCO_15") (pintype "power_in"))
    (pad "B19" smd circle (at 5.499 -11.5 180) (size 0.5 0.5) (layers "F.Cu" "F.Paste" "F.Mask")
      (net 426 "FMC_IO_4_N") (pinfunction "IO_L4N_T0_AD9N_15") (pintype "bidirectional") (die_length 18.77))
    (pad "B20" smd circle (at 6.499 -11.5 180) (size 0.5 0.5) (layers "F.Cu" "F.Paste" "F.Mask")
      (net 70 "USR_LED2") (pinfunction "IO_L8P_T1_D11_14") (pintype "bidirectional") (die_length 20.881))
    (pad "B21" smd circle (at 7.499 -11.5 180) (size 0.5 0.5) (layers "F.Cu" "F.Paste" "F.Mask")
      (net 68 "USR_LED3") (pinfunction "IO_L10N_T1_D15_14") (pintype "bidirectional") (die_length 22.228))
    (pad "B22" smd circle (at 8.499 -11.5 180) (size 0.5 0.5) (layers "F.Cu" "F.Paste" "F.Mask")
      (net 21 "QSPI_DQ2") (pinfunction "IO_L2P_T0_D02_14") (pintype "bidirectional") (die_length 20.4))
    (pad "B23" smd circle (at 9.499 -11.5 180) (size 0.5 0.5) (layers "F.Cu" "F.Paste" "F.Mask")
      (net 9 "GND") (pinfunction "GND") (pintype "passive"))
    (pad "B24" smd circle (at 10.499 -11.5 180) (size 0.5 0.5) (layers "F.Cu" "F.Paste" "F.Mask")
      (net 19 "QSPI_DQ0") (pinfunction "IO_L1P_T0_D00_MOSI_14") (pintype "bidirectional") (die_length 22.518))
    (pad "B25" smd circle (at 11.499 -11.5 180) (size 0.5 0.5) (layers "F.Cu" "F.Paste" "F.Mask")
      (net 79 "PUDC_B") (pinfunction "IO_L3P_T0_DQS_PUDC_B_14") (pintype "bidirectional") (die_length 23.894))
    (pad "B26" smd circle (at 12.499 -11.5 180) (size 0.5 0.5) (layers "F.Cu" "F.Paste" "F.Mask")
      (net 99 "EMCCLK") (pinfunction "IO_L3N_T0_DQS_EMCCLK_14") (pintype "bidirectional") (die_length 24.039))
    (pad "C1" smd circle (at -12.5 -10.5 180) (size 0.5 0.5) (layers "F.Cu" "F.Paste" "F.Mask")
      (net 9 "GND") (pinfunction "GND") (pintype "passive"))
    (pad "C2" smd circle (at -11.5 -10.5 180) (size 0.5 0.5) (layers "F.Cu" "F.Paste" "F.Mask")
      (net 306 "1V2_SYS") (pinfunction "MGTAVTT") (pintype "passive"))
    (pad "C3" smd circle (at -10.5 -10.5 180) (size 0.5 0.5) (layers "F.Cu" "F.Paste" "F.Mask")
      (net 633 "GTX_RX1_N") (pinfunction "MGTXRXN2_116") (pintype "bidirectional") (die_length 14.495))
    (pad "C4" smd circle (at -9.5 -10.5 180) (size 0.5 0.5) (layers "F.Cu" "F.Paste" "F.Mask")
      (net 632 "GTX_RX1_P") (pinfunction "MGTXRXP2_116") (pintype "bidirectional") (die_length 14.581))
    (pad "C5" smd circle (at -8.5 -10.5 180) (size 0.5 0.5) (layers "F.Cu" "F.Paste" "F.Mask")
      (net 9 "GND") (pinfunction "GND") (pintype "passive"))
    (pad "C6" smd circle (at -7.5 -10.5 180) (size 0.5 0.5) (layers "F.Cu" "F.Paste" "F.Mask")
      (net 147 "1V0_SYS") (pinfunction "MGTAVCC") (pintype "power_in"))
    (pad "C7" smd circle (at -6.5 -10.5 180) (size 0.5 0.5) (layers "F.Cu" "F.Paste" "F.Mask")
      (net 9 "GND") (pinfunction "GND") (pintype "passive"))
    (pad "C8" smd circle (at -5.5 -10.5 180) (size 0.5 0.5) (layers "F.Cu" "F.Paste" "F.Mask")
      (net 96 "CCLK") (pinfunction "CCLK_0") (pintype "bidirectional") (die_length 21.831))
    (pad "C9" smd circle (at -4.5 -10.5 180) (size 0.5 0.5) (layers "F.Cu" "F.Paste" "F.Mask")
      (net 87 "SD_DAT2") (pinfunction "IO_L10P_T1_16") (pintype "bidirectional") (die_length 20.913))
    (pad "C10" smd circle (at -3.5 -10.5 180) (size 0.5 0.5) (layers "F.Cu" "F.Paste" "F.Mask")
      (net 9 "GND") (pinfunction "GND") (pintype "passive"))
    (pad "C11" smd circle (at -2.5 -10.5 180) (size 0.5 0.5) (layers "F.Cu" "F.Paste" "F.Mask")
      (net 727 "unconnected-(U15E-IO_L13N_T2_MRCC_16-PadC11)") (pinfunction "IO_L13N_T2_MRCC_16") (pintype "bidirectional+no_connect") (die_length 19.377))
    (pad "C12" smd circle (at -1.5 -10.5 180) (size 0.5 0.5) (layers "F.Cu" "F.Paste" "F.Mask")
      (net 311 "GCLK100") (pinfunction "IO_L13P_T2_MRCC_16") (pintype "bidirectional") (die_length 19.317))
    (pad "C13" smd circle (at -0.5 -10.5 180) (size 0.5 0.5) (layers "F.Cu" "F.Paste" "F.Mask")
      (net 728 "unconnected-(U15E-IO_L19N_T3_VREF_16-PadC13)") (pinfunction "IO_L19N_T3_VREF_16") (pintype "bidirectional+no_connect") (die_length 16.263))
    (pad "C14" smd circle (at 0.499 -10.5 180) (size 0.5 0.5) (layers "F.Cu" "F.Paste" "F.Mask")
      (net 729 "unconnected-(U15E-IO_L19P_T3_16-PadC14)") (pinfunction "IO_L19P_T3_16") (pintype "bidirectional+no_connect") (die_length 15.843))
    (pad "C15" smd circle (at 1.499 -10.5 180) (size 0.5 0.5) (layers "F.Cu" "F.Paste" "F.Mask")
      (net 143 "3V3_SYS") (pinfunction "VCCO_16") (pintype "passive"))
    (pad "C16" smd circle (at 2.499 -10.5 180) (size 0.5 0.5) (layers "F.Cu" "F.Paste" "F.Mask")
      (net 427 "FMC_IO_1_P") (pinfunction "IO_L1P_T0_AD0P_15") (pintype "bidirectional") (die_length 14.788))
    (pad "C17" smd circle (at 3.499 -10.5 180) (size 0.5 0.5) (layers "F.Cu" "F.Paste" "F.Mask")
      (net 428 "FMC_IO_5_P") (pinfunction "IO_L5P_T0_AD2P_15") (pintype "bidirectional") (die_length 15.703))
    (pad "C18" smd circle (at 4.499 -10.5 180) (size 0.5 0.5) (layers "F.Cu" "F.Paste" "F.Mask")
      (net 435 "FMC_IO_5_N") (pinfunction "IO_L5N_T0_AD2N_15") (pintype "bidirectional") (die_length 17.41))
    (pad "C19" smd circle (at 5.499 -10.5 180) (size 0.5 0.5) (layers "F.Cu" "F.Paste" "F.Mask")
      (net 436 "FMC_IO_4_P") (pinfunction "IO_L4P_T0_AD9P_15") (pintype "bidirectional") (die_length 16.927))
    (pad "C20" smd circle (at 6.499 -10.5 180) (size 0.5 0.5) (layers "F.Cu" "F.Paste" "F.Mask")
      (net 9 "GND") (pinfunction "GND") (pintype "passive"))
    (pad "C21" smd circle (at 7.499 -10.5 180) (size 0.5 0.5) (layers "F.Cu" "F.Paste" "F.Mask")
      (net 149 "HOT_SWAP_BUTTON") (pinfunction "IO_L10P_T1_D14_14") (pintype "bidirectional") (die_length 20.52))
    (pad "C22" smd circle (at 8.499 -10.5 180) (size 0.5 0.5) (layers "F.Cu" "F.Paste" "F.Mask")
      (net 72 "USR_LED4") (pinfunction "IO_L7N_T1_D10_14") (pintype "bidirectional") (die_length 20.673))
    (pad "C23" smd circle (at 9.499 -10.5 180) (size 0.5 0.5) (layers "F.Cu" "F.Paste" "F.Mask")
      (net 95 "FCS_B") (pinfunction "IO_L6P_T0_FCS_B_14") (pintype "bidirectional") (die_length 20.723))
    (pad "C24" smd circle (at 10.499 -10.5 180) (size 0.5 0.5) (layers "F.Cu" "F.Paste" "F.Mask")
      (net 126 "AUX_JTAG_TCK") (pinfunction "IO_L6N_T0_D08_VREF_14") (pintype "bidirectional") (die_length 22.056))
    (pad "C25" smd circle (at 11.499 -10.5 180) (size 0.5 0.5) (layers "F.Cu" "F.Paste" "F.Mask")
      (net 143 "3V3_SYS") (pinfunction "VCCO_14") (pintype "passive"))
    (pad "C26" smd circle (at 12.499 -10.5 180) (size 0.5 0.5) (layers "F.Cu" "F.Paste" "F.Mask")
      (net 146 "AUX_JTAG_TDO") (pinfunction "IO_L5N_T0_D07_14") (pintype "bidirectional") (die_length 24.432))
    (pad "D1" smd circle (at -12.5 -9.5 180) (size 0.5 0.5) (layers "F.Cu" "F.Paste" "F.Mask")
      (net 439 "GTX_TX2_N") (pinfunction "MGTXTXN1_116") (pintype "bidirectional") (die_length 15.23))
    (pad "D2" smd circle (at -11.5 -9.5 180) (size 0.5 0.5) (layers "F.Cu" "F.Paste" "F.Mask")
      (net 431 "GTX_TX2_P") (pinfunction "MGTXTXP1_116") (pintype "bidirectional") (die_length 15.219))
    (pad "D3" smd circle (at -10.5 -9.5 180) (size 0.5 0.5) (layers "F.Cu" "F.Paste" "F.Mask")
      (net 306 "1V2_SYS") (pinfunction "MGTAVTT") (pintype "passive"))
    (pad "D4" smd circle (at -9.5 -9.5 180) (size 0.5 0.5) (layers "F.Cu" "F.Paste" "F.Mask")
      (net 9 "GND") (pinfunction "GND") (pintype "passive"))
    (pad "D5" smd circle (at -8.5 -9.5 180) (size 0.5 0.5) (layers "F.Cu" "F.Paste" "F.Mask")
      (net 886 "/FPGA banks 115-116/GTR_REFCLK2_N") (pinfunction "MGTREFCLK0N_116") (pintype "bidirectional") (die_length 13.229))
    (pad "D6" smd circle (at -7.5 -9.5 180) (size 0.5 0.5) (layers "F.Cu" "F.Paste" "F.Mask")
      (net 885 "/FPGA banks 115-116/GTR_REFCLK2_P") (pinfunction "MGTREFCLK0P_116") (pintype "bidirectional") (die_length 13.265))
    (pad "D7" smd circle (at -6.5 -9.5 180) (size 0.5 0.5) (layers "F.Cu" "F.Paste" "F.Mask")
      (net 9 "GND") (pinfunction "GND") (pintype "passive"))
    (pad "D8" smd circle (at -5.5 -9.5 180) (size 0.5 0.5) (layers "F.Cu" "F.Paste" "F.Mask")
      (net 85 "SD_CMD") (pinfunction "IO_L8N_T1_16") (pintype "bidirectional") (die_length 19.972))
    (pad "D9" smd circle (at -4.5 -9.5 180) (size 0.5 0.5) (layers "F.Cu" "F.Paste" "F.Mask")
      (net 86 "SD_DAT3") (pinfunction "IO_L8P_T1_16") (pintype "bidirectional") (die_length 18.666))
    (pad "D10" smd circle (at -3.5 -9.5 180) (size 0.5 0.5) (layers "F.Cu" "F.Paste" "F.Mask")
      (net 84 "SD_CLK") (pinfunction "IO_L12N_T1_MRCC_16") (pintype "bidirectional") (die_length 17.142))
    (pad "D11" smd circle (at -2.5 -9.5 180) (size 0.5 0.5) (layers "F.Cu" "F.Paste" "F.Mask")
      (net 730 "unconnected-(U15E-IO_L14N_T2_SRCC_16-PadD11)") (pinfunction "IO_L14N_T2_SRCC_16") (pintype "bidirectional+no_connect") (die_length 15.596))
    (pad "D12" smd circle (at -1.5 -9.5 180) (size 0.5 0.5) (layers "F.Cu" "F.Paste" "F.Mask")
      (net 143 "3V3_SYS") (pinfunction "VCCO_16") (pintype "passive"))
    (pad "D13" smd circle (at -0.5 -9.5 180) (size 0.5 0.5) (layers "F.Cu" "F.Paste" "F.Mask")
      (net 731 "unconnected-(U15E-IO_L17N_T2_16-PadD13)") (pinfunction "IO_L17N_T2_16") (pintype "bidirectional+no_connect") (die_length 16.197))
    (pad "D14" smd circle (at 0.499 -9.5 180) (size 0.5 0.5) (layers "F.Cu" "F.Paste" "F.Mask")
      (net 732 "unconnected-(U15E-IO_L17P_T2_16-PadD14)") (pinfunction "IO_L17P_T2_16") (pintype "bidirectional+no_connect") (die_length 15.301))
    (pad "D15" smd circle (at 1.499 -9.5 180) (size 0.5 0.5) (layers "F.Cu" "F.Paste" "F.Mask")
      (net 437 "FMC_IO_6_P") (pinfunction "IO_L6P_T0_15") (pintype "bidirectional") (die_length 17.491))
    (pad "D16" smd circle (at 2.499 -9.5 180) (size 0.5 0.5) (layers "F.Cu" "F.Paste" "F.Mask")
      (net 444 "FMC_IO_6_N") (pinfunction "IO_L6N_T0_VREF_15") (pintype "bidirectional") (die_length 17.595))
    (pad "D17" smd circle (at 3.499 -9.5 180) (size 0.5 0.5) (layers "F.Cu" "F.Paste" "F.Mask")
      (net 9 "GND") (pinfunction "GND") (pintype "passive"))
    (pad "D18" smd circle (at 4.499 -9.5 180) (size 0.5 0.5) (layers "F.Cu" "F.Paste" "F.Mask")
      (net 445 "FMC_IO_13_N") (pinfunction "IO_L13N_T2_MRCC_15") (pintype "bidirectional") (die_length 16.746))
    (pad "D19" smd circle (at 5.499 -9.5 180) (size 0.5 0.5) (layers "F.Cu" "F.Paste" "F.Mask")
      (net 446 "FMC_IO_15_P") (pinfunction "IO_L15P_T2_DQS_15") (pintype "bidirectional") (die_length 16.273))
    (pad "D20" smd circle (at 6.499 -9.5 180) (size 0.5 0.5) (layers "F.Cu" "F.Paste" "F.Mask")
      (net 447 "FMC_IO_15_N") (pinfunction "IO_L15N_T2_DQS_ADV_B_15") (pintype "bidirectional") (die_length 16.189))
    (pad "D21" smd circle (at 7.499 -9.5 180) (size 0.5 0.5) (layers "F.Cu" "F.Paste" "F.Mask")
      (net 67 "USR_LED1") (pinfunction "IO_L7P_T1_D09_14") (pintype "bidirectional") (die_length 20.735))
    (pad "D22" smd circle (at 8.499 -9.5 180) (size 0.5 0.5) (layers "F.Cu" "F.Paste" "F.Mask")
      (net 143 "3V3_SYS") (pinfunction "VCCO_14") (pintype "passive"))
    (pad "D23" smd circle (at 9.499 -9.5 180) (size 0.5 0.5) (layers "F.Cu" "F.Paste" "F.Mask")
      (net 786 "HOT_SWAP_GREEN") (pinfunction "IO_L11P_T1_SRCC_14") (pintype "bidirectional") (die_length 20.085))
    (pad "D24" smd circle (at 10.499 -9.5 180) (size 0.5 0.5) (layers "F.Cu" "F.Paste" "F.Mask")
      (net 128 "AUX_JTAG_TDI") (pinfunction "IO_L11N_T1_SRCC_14") (pintype "bidirectional") (die_length 20.314))
    (pad "D25" smd circle (at 11.499 -9.5 180) (size 0.5 0.5) (layers "F.Cu" "F.Paste" "F.Mask")
      (net 131 "AUX_JTAG_TMS") (pinfunction "IO_L15N_T2_DQS_DOUT_CSO_B_14") (pintype "bidirectional") (die_length 20.821))
    (pad "D26" smd circle (at 12.499 -9.5 180) (size 0.5 0.5) (layers "F.Cu" "F.Paste" "F.Mask")
      (net 357 "SDA_3V3") (pinfunction "IO_L5P_T0_D06_14") (pintype "bidirectional") (die_length 24.394))
    (pad "E1" smd circle (at -12.5 -8.5 180) (size 0.5 0.5) (layers "F.Cu" "F.Paste" "F.Mask")
      (net 9 "GND") (pinfunction "GND") (pintype "passive"))
    (pad "E2" smd circle (at -11.5 -8.5 180) (size 0.5 0.5) (layers "F.Cu" "F.Paste" "F.Mask")
      (net 9 "GND") (pinfunction "GND") (pintype "passive"))
    (pad "E3" smd circle (at -10.5 -8.5 180) (size 0.5 0.5) (layers "F.Cu" "F.Paste" "F.Mask")
      (net 635 "GTX_RX2_N") (pinfunction "MGTXRXN1_116") (pintype "bidirectional") (die_length 13.353))
    (pad "E4" smd circle (at -9.5 -8.5 180) (size 0.5 0.5) (layers "F.Cu" "F.Paste" "F.Mask")
      (net 634 "GTX_RX2_P") (pinfunction "MGTXRXP1_116") (pintype "bidirectional") (die_length 13.435))
    (pad "E5" smd circle (at -8.5 -8.5 180) (size 0.5 0.5) (layers "F.Cu" "F.Paste" "F.Mask")
      (net 9 "GND") (pinfunction "GND") (pintype "passive"))
    (pad "E6" smd circle (at -7.5 -8.5 180) (size 0.5 0.5) (layers "F.Cu" "F.Paste" "F.Mask")
      (net 147 "1V0_SYS") (pinfunction "MGTAVCC") (pintype "passive"))
    (pad "E7" smd circle (at -6.5 -8.5 180) (size 0.5 0.5) (layers "F.Cu" "F.Paste" "F.Mask")
      (net 9 "GND") (pinfunction "GND") (pintype "passive"))
  )
)
